(kicad_pcb
	(version 20241229)
	(generator "pcbnew")
	(generator_version "9.0")
	(general
		(thickness 1.711)
		(legacy_teardrops no)
	)
	(paper "A4")
	(title_block
		(title "Antmicro Baseboard for Jetson AGX Thor")
		(date "2026-02-18")
		(rev "1.1.0")
		(company "Antmicro Ltd")
		(comment 1 "www.antmicro.com")
		(comment 9 "footprints 413-416 of 1170")
	)
	(layers
		(0 "F.Cu" signal)
		(4 "In1.Cu" signal)
		(6 "In2.Cu" signal)
		(8 "In3.Cu" signal)
		(10 "In4.Cu" jumper)
		(12 "In5.Cu" signal)
		(14 "In6.Cu" signal)
		(16 "In7.Cu" signal)
		(18 "In8.Cu" signal)
		(2 "B.Cu" signal)
		(9 "F.Adhes" user "F.Adhesive")
		(11 "B.Adhes" user "B.Adhesive")
		(13 "F.Paste" user)
		(15 "B.Paste" user)
		(5 "F.SilkS" user "F.Silkscreen")
		(7 "B.SilkS" user "B.Silkscreen")
		(1 "F.Mask" user)
		(3 "B.Mask" user)
		(17 "Dwgs.User" user "User.Drawings")
		(19 "Cmts.User" user "User.Comments")
		(21 "Eco1.User" user "User.Eco1")
		(23 "Eco2.User" user "User.Eco2")
		(25 "Edge.Cuts" user)
		(27 "Margin" user)
		(31 "F.CrtYd" user "F.Courtyard")
		(29 "B.CrtYd" user "B.Courtyard")
		(35 "F.Fab" user)
		(33 "B.Fab" user)
	)
	(footprint "antmicro-footprints:C_0402_1005Metric"
		(layer "F.Cu")
		(at 61 92.3 -90)
		(descr "Capacitor SMD 0402")
		(tags "capacitor SMD 0402")
		(property "Reference" "C164"
			(at -1.4 -0.7 90)
			(layer "F.SilkS")
			(effects
				(font
					(size 0.7 0.7)
					(thickness 0.15)
				)
				(justify right top)
			)
		)
		(property "Value" "C_1u_0402"
			(at -1.022927 2.155213 90)
			(layer "F.Fab")
			(effects
				(font
					(size 0.7 0.7)
					(thickness 0.15)
				)
				(justify right top)
			)
		)
		(property "Datasheet" "https://product.tdk.com/en/search/capacitor/ceramic/mlcc/info?part_no=C1005X6S1A105K050BC"
			(at 0 0 90)
			(layer "F.Fab")
			(hide yes)
			(effects
				(font
					(size 1.27 1.27)
					(thickness 0.15)
				)
			)
		)
		(property "Description" "SMD Multilayer Ceramic Capacitor, 1 µF, 10 V, 0402 [1005 Metric], ± 10%, X6S, C"
			(at 0 0 90)
			(layer "F.Fab")
			(hide yes)
			(effects
				(font
					(size 1.27 1.27)
					(thickness 0.15)
				)
			)
		)
		(property "Manufacturer" "TDK"
			(at 0 0 270)
			(unlocked yes)
			(layer "F.Fab")
			(hide yes)
			(effects
				(font
					(size 1 1)
					(thickness 0.15)
				)
			)
		)
		(property "MPN" "C1005X6S1A105K050BC"
			(at 0 0 270)
			(unlocked yes)
			(layer "F.Fab")
			(hide yes)
			(effects
				(font
					(size 1 1)
					(thickness 0.15)
				)
			)
		)
		(property "Val" "1u"
			(at 0 0 270)
			(unlocked yes)
			(layer "F.Fab")
			(hide yes)
			(effects
				(font
					(size 1 1)
					(thickness 0.15)
				)
			)
		)
		(property "License" "Apache-2.0"
			(at 0 0 270)
			(unlocked yes)
			(layer "F.Fab")
			(hide yes)
			(effects
				(font
					(size 1 1)
					(thickness 0.15)
				)
			)
		)
		(property "Author" "Antmicro"
			(at 0 0 270)
			(unlocked yes)
			(layer "F.Fab")
			(hide yes)
			(effects
				(font
					(size 1 1)
					(thickness 0.15)
				)
			)
		)
		(property "Voltage" ""
			(at 0 0 270)
			(unlocked yes)
			(layer "F.Fab")
			(hide yes)
			(effects
				(font
					(size 1 1)
					(thickness 0.15)
				)
			)
		)
		(property "Dielectric" ""
			(at 0 0 270)
			(unlocked yes)
			(layer "F.Fab")
			(hide yes)
			(effects
				(font
					(size 1 1)
					(thickness 0.15)
				)
			)
		)
		(sheetname "/CSI/")
		(sheetfile "csi.kicad_sch")
		(attr smd)
		(fp_poly
			(pts
				(xy -0.925 -0.47) (xy 0.925 -0.47) (xy 0.925 0.47) (xy -0.925 0.47)
			)
			(stroke
				(width 0.05)
				(type default)
			)
			(fill no)
			(layer "F.CrtYd")
		)
		(fp_line
			(start -0.494 0.248)
			(end -0.494 -0.25)
			(stroke
				(width 0.15)
				(type solid)
			)
			(layer "F.Fab")
		)
		(fp_line
			(start 0.504 0.248)
			(end -0.494 0.248)
			(stroke
				(width 0.15)
				(type solid)
			)
			(layer "F.Fab")
		)
		(fp_line
			(start -0.494 -0.25)
			(end 0.504 -0.25)
			(stroke
				(width 0.15)
				(type solid)
			)
			(layer "F.Fab")
		)
		(fp_line
			(start 0.504 -0.25)
			(end 0.504 0.248)
			(stroke
				(width 0.15)
				(type solid)
			)
			(layer "F.Fab")
		)
		(fp_text user "License: Apache-2.0"
			(at -0.939 5.799 90)
			(layer "F.Fab")
			(effects
				(font
					(size 0.7 0.7)
					(thickness 0.15)
				)
				(justify right top)
			)
		)
		(fp_text user "${REFERENCE}"
			(at -0.939 4.599 90)
			(layer "F.Fab")
			(effects
				(font
					(size 0.7 0.7)
					(thickness 0.15)
				)
				(justify right top)
			)
		)
		(fp_text user "Author: Antmicro"
			(at -0.939 3.399 90)
			(layer "F.Fab")
			(effects
				(font
					(size 0.7 0.7)
					(thickness 0.15)
				)
				(justify right top)
			)
		)
		(pad "1" smd roundrect
			(at -0.48 0 270)
			(size 0.59 0.64)
			(layers "F.Cu" "F.Mask" "F.Paste")
			(roundrect_rratio 0.25)
			(net 1 "GND")
			(pintype "passive")
		)
		(pad "2" smd roundrect
			(at 0.48 0 270)
			(size 0.59 0.64)
			(layers "F.Cu" "F.Mask" "F.Paste")
			(roundrect_rratio 0.25)
			(net 6 "/CSI/CSIA_3V3")
			(pintype "passive")
		)
	)
	(footprint "antmicro-footprints:C_0402_1005Metric"
		(layer "F.Cu")
		(at 205.6 82.5)
		(descr "Capacitor SMD 0402")
		(tags "capacitor SMD 0402")
		(property "Reference" "C136"
			(at 0.8 0.4 0)
			(layer "F.SilkS")
			(effects
				(font
					(size 0.7 0.7)
					(thickness 0.15)
				)
				(justify left bottom)
			)
		)
		(property "Value" "C_100n_0402"
			(at -1.022927 2.155213 0)
			(layer "F.Fab")
			(effects
				(font
					(size 0.7 0.7)
					(thickness 0.15)
				)
				(justify left bottom)
			)
		)
		(property "Datasheet" "https://www.murata.com/products/productdetail?partno=GRM155R61H104KE14%23"
			(at 0 0 0)
			(layer "F.Fab")
			(hide yes)
			(effects
				(font
					(size 1.27 1.27)
					(thickness 0.15)
				)
			)
		)
		(property "Description" "SMD Multilayer Ceramic Capacitor, 0.1 µF, 50 V, 0402 [1005 Metric], ± 10%, X5R, GRM Series"
			(at 0 0 0)
			(layer "F.Fab")
			(hide yes)
			(effects
				(font
					(size 1.27 1.27)
					(thickness 0.15)
				)
			)
		)
		(property "MPN" "GRM155R61H104KE14D"
			(at 0 0 0)
			(unlocked yes)
			(layer "F.Fab")
			(hide yes)
			(effects
				(font
					(size 1 1)
					(thickness 0.15)
				)
			)
		)
		(property "Manufacturer" "Murata"
			(at 0 0 0)
			(unlocked yes)
			(layer "F.Fab")
			(hide yes)
			(effects
				(font
					(size 1 1)
					(thickness 0.15)
				)
			)
		)
		(property "Val" "100n"
			(at 0 0 0)
			(unlocked yes)
			(layer "F.Fab")
			(hide yes)
			(effects
				(font
					(size 1 1)
					(thickness 0.15)
				)
			)
		)
		(property "License" "Apache-2.0"
			(at 0 0 0)
			(unlocked yes)
			(layer "F.Fab")
			(hide yes)
			(effects
				(font
					(size 1 1)
					(thickness 0.15)
				)
			)
		)
		(property "Author" "Antmicro"
			(at 0 0 0)
			(unlocked yes)
			(layer "F.Fab")
			(hide yes)
			(effects
				(font
					(size 1 1)
					(thickness 0.15)
				)
			)
		)
		(property "Voltage" "50V"
			(at 0 0 0)
			(unlocked yes)
			(layer "F.Fab")
			(hide yes)
			(effects
				(font
					(size 1 1)
					(thickness 0.15)
				)
			)
		)
		(property "Dielectric" "X5R"
			(at 0 0 0)
			(unlocked yes)
			(layer "F.Fab")
			(hide yes)
			(effects
				(font
					(size 1 1)
					(thickness 0.15)
				)
			)
		)
		(sheetname "/USB DP Alt mode/")
		(sheetfile "usb_dp.kicad_sch")
		(attr smd)
		(fp_poly
			(pts
				(xy -0.925 -0.47) (xy 0.925 -0.47) (xy 0.925 0.47) (xy -0.925 0.47)
			)
			(stroke
				(width 0.05)
				(type default)
			)
			(fill no)
			(layer "F.CrtYd")
		)
		(fp_line
			(start -0.494 -0.25)
			(end 0.504 -0.25)
			(stroke
				(width 0.15)
				(type solid)
			)
			(layer "F.Fab")
		)
		(fp_line
			(start -0.494 0.248)
			(end -0.494 -0.25)
			(stroke
				(width 0.15)
				(type solid)
			)
			(layer "F.Fab")
		)
		(fp_line
			(start 0.504 -0.25)
			(end 0.504 0.248)
			(stroke
				(width 0.15)
				(type solid)
			)
			(layer "F.Fab")
		)
		(fp_line
			(start 0.504 0.248)
			(end -0.494 0.248)
			(stroke
				(width 0.15)
				(type solid)
			)
			(layer "F.Fab")
		)
		(fp_text user "${REFERENCE}"
			(at -0.939 4.599 0)
			(layer "F.Fab")
			(effects
				(font
					(size 0.7 0.7)
					(thickness 0.15)
				)
				(justify left bottom)
			)
		)
		(fp_text user "Author: Antmicro"
			(at -0.939 3.399 0)
			(layer "F.Fab")
			(effects
				(font
					(size 0.7 0.7)
					(thickness 0.15)
				)
				(justify left bottom)
			)
		)
		(fp_text user "License: Apache-2.0"
			(at -0.939 5.799 0)
			(layer "F.Fab")
			(effects
				(font
					(size 0.7 0.7)
					(thickness 0.15)
				)
				(justify left bottom)
			)
		)
		(pad "1" smd roundrect
			(at -0.48 0)
			(size 0.59 0.64)
			(layers "F.Cu" "F.Mask" "F.Paste")
			(roundrect_rratio 0.25)
			(net 522 "/Power/USBPD1_HV")
			(pintype "passive")
		)
		(pad "2" smd roundrect
			(at 0.48 0)
			(size 0.59 0.64)
			(layers "F.Cu" "F.Mask" "F.Paste")
			(roundrect_rratio 0.25)
			(net 1 "GND")
			(pintype "passive")
		)
	)
	(footprint "antmicro-footprints:C_0402_1005Metric"
		(layer "F.Cu")
		(at 216.6 84.3 90)
		(descr "Capacitor SMD 0402")
		(tags "capacitor SMD 0402")
		(property "Reference" "C126"
			(at 0.9 0.4 90)
			(layer "F.SilkS")
			(effects
				(font
					(size 0.7 0.7)
					(thickness 0.15)
				)
				(justify left bottom)
			)
		)
		(property "Value" "C_100n_0402"
			(at -1.022927 2.155213 90)
			(layer "F.Fab")
			(effects
				(font
					(size 0.7 0.7)
					(thickness 0.15)
				)
				(justify left bottom)
			)
		)
		(property "Datasheet" "https://www.murata.com/products/productdetail?partno=GRM155R61H104KE14%23"
			(at 0 0 90)
			(layer "F.Fab")
			(hide yes)
			(effects
				(font
					(size 1.27 1.27)
					(thickness 0.15)
				)
			)
		)
		(property "Description" "SMD Multilayer Ceramic Capacitor, 0.1 µF, 50 V, 0402 [1005 Metric], ± 10%, X5R, GRM Series"
			(at 0 0 90)
			(layer "F.Fab")
			(hide yes)
			(effects
				(font
					(size 1.27 1.27)
					(thickness 0.15)
				)
			)
		)
		(property "Manufacturer" "Murata"
			(at 0 0 90)
			(unlocked yes)
			(layer "F.Fab")
			(hide yes)
			(effects
				(font
					(size 1 1)
					(thickness 0.15)
				)
			)
		)
		(property "MPN" "GRM155R61H104KE14D"
			(at 0 0 90)
			(unlocked yes)
			(layer "F.Fab")
			(hide yes)
			(effects
				(font
					(size 1 1)
					(thickness 0.15)
				)
			)
		)
		(property "Val" "100n"
			(at 0 0 90)
			(unlocked yes)
			(layer "F.Fab")
			(hide yes)
			(effects
				(font
					(size 1 1)
					(thickness 0.15)
				)
			)
		)
		(property "License" "Apache-2.0"
			(at 0 0 90)
			(unlocked yes)
			(layer "F.Fab")
			(hide yes)
			(effects
				(font
					(size 1 1)
					(thickness 0.15)
				)
			)
		)
		(property "Author" "Antmicro"
			(at 0 0 90)
			(unlocked yes)
			(layer "F.Fab")
			(hide yes)
			(effects
				(font
					(size 1 1)
					(thickness 0.15)
				)
			)
		)
		(property "Voltage" "50V"
			(at 0 0 90)
			(unlocked yes)
			(layer "F.Fab")
			(hide yes)
			(effects
				(font
					(size 1 1)
					(thickness 0.15)
				)
			)
		)
		(property "Dielectric" "X5R"
			(at 0 0 90)
			(unlocked yes)
			(layer "F.Fab")
			(hide yes)
			(effects
				(font
					(size 1 1)
					(thickness 0.15)
				)
			)
		)
		(sheetname "/USB DP Alt mode/")
		(sheetfile "usb_dp.kicad_sch")
		(attr smd)
		(fp_poly
			(pts
				(xy -0.925 -0.47) (xy -0.925 0.47) (xy 0.925 0.47) (xy 0.925 -0.47)
			)
			(stroke
				(width 0.05)
				(type default)
			)
			(fill no)
			(layer "F.CrtYd")
		)
		(fp_line
			(start 0.504 -0.25)
			(end 0.504 0.248)
			(stroke
				(width 0.15)
				(type solid)
			)
			(layer "F.Fab")
		)
		(fp_line
			(start -0.494 -0.25)
			(end 0.504 -0.25)
			(stroke
				(width 0.15)
				(type solid)
			)
			(layer "F.Fab")
		)
		(fp_line
			(start 0.504 0.248)
			(end -0.494 0.248)
			(stroke
				(width 0.15)
				(type solid)
			)
			(layer "F.Fab")
		)
		(fp_line
			(start -0.494 0.248)
			(end -0.494 -0.25)
			(stroke
				(width 0.15)
				(type solid)
			)
			(layer "F.Fab")
		)
		(fp_text user "License: Apache-2.0"
			(at -0.939 5.799 90)
			(layer "F.Fab")
			(effects
				(font
					(size 0.7 0.7)
					(thickness 0.15)
				)
				(justify left bottom)
			)
		)
		(fp_text user "${REFERENCE}"
			(at -0.939 4.599 90)
			(layer "F.Fab")
			(effects
				(font
					(size 0.7 0.7)
					(thickness 0.15)
				)
				(justify left bottom)
			)
		)
		(fp_text user "Author: Antmicro"
			(at -0.939 3.399 90)
			(layer "F.Fab")
			(effects
				(font
					(size 0.7 0.7)
					(thickness 0.15)
				)
				(justify left bottom)
			)
		)
		(pad "1" smd roundrect
			(at -0.48 0 90)
			(size 0.59 0.64)
			(layers "F.Cu" "F.Mask" "F.Paste")
			(roundrect_rratio 0.25)
			(net 2 "+3V3")
			(pintype "passive")
		)
		(pad "2" smd roundrect
			(at 0.48 0 90)
			(size 0.59 0.64)
			(layers "F.Cu" "F.Mask" "F.Paste")
			(roundrect_rratio 0.25)
			(net 1 "GND")
			(pintype "passive")
		)
	)
	(footprint "antmicro-footprints:C_0805_2012Metric"
		(layer "F.Cu")
		(at 171.34 73.32 -90)
		(descr "Capacitor SMD 0805")
		(tags "capacitor SMD 0805")
		(property "Reference" "C285"
			(at 1.78449 -1.468678 90)
			(layer "F.SilkS")
			(effects
				(font
					(size 0.7 0.7)
					(thickness 0.15)
				)
				(justify right top)
			)
		)
		(property "Value" "C_22u_25V_0805"
			(at -2.055717 1.963152 90)
			(layer "F.Fab")
			(effects
				(font
					(size 0.7 0.7)
					(thickness 0.15)
				)
				(justify right top)
			)
		)
		(property "Datasheet" "https://product.samsungsem.com/mlcc/CL21A226MAYNNN.do"
			(at 0 0 90)
			(layer "F.Fab")
			(hide yes)
			(effects
				(font
					(size 1.27 1.27)
					(thickness 0.15)
				)
			)
		)
		(property "Description" "SMT Multilayer Ceramic Capacitor, 22uF, +/-20%, 25V, X5R, 0805 [2012 Metric]"
			(at 0 0 90)
			(layer "F.Fab")
			(hide yes)
			(effects
				(font
					(size 1.27 1.27)
					(thickness 0.15)
				)
			)
		)
		(property "MPN" "CL21A226MAYNNNE"
			(at 0 0 270)
			(unlocked yes)
			(layer "F.Fab")
			(hide yes)
			(effects
				(font
					(size 1 1)
					(thickness 0.15)
				)
			)
		)
		(property "Manufacturer" "Samsung Electro-Mechanics"
			(at 0 0 270)
			(unlocked yes)
			(layer "F.Fab")
			(hide yes)
			(effects
				(font
					(size 1 1)
					(thickness 0.15)
				)
			)
		)
		(property "License" "Apache-2.0"
			(at 0 0 270)
			(unlocked yes)
			(layer "F.Fab")
			(hide yes)
			(effects
				(font
					(size 1 1)
					(thickness 0.15)
				)
			)
		)
		(property "Author" "Antmicro"
			(at 0 0 270)
			(unlocked yes)
			(layer "F.Fab")
			(hide yes)
			(effects
				(font
					(size 1 1)
					(thickness 0.15)
				)
			)
		)
		(property "Val" "22u"
			(at 0 0 270)
			(unlocked yes)
			(layer "F.Fab")
			(hide yes)
			(effects
				(font
					(size 1 1)
					(thickness 0.15)
				)
			)
		)
		(property "Voltage" "25V"
			(at 0 0 270)
			(unlocked yes)
			(layer "F.Fab")
			(hide yes)
			(effects
				(font
					(size 1 1)
					(thickness 0.15)
				)
			)
		)
		(property "Dielectric" "X5R"
			(at 0 0 270)
			(unlocked yes)
			(layer "F.Fab")
			(hide yes)
			(effects
				(font
					(size 1 1)
					(thickness 0.15)
				)
			)
		)
		(property "Public" "False"
			(at 0 0 270)
			(unlocked yes)
			(layer "F.Fab")
			(hide yes)
			(effects
				(font
					(size 1 1)
					(thickness 0.15)
				)
			)
		)
		(component_classes
			(class "DCDC_20V")
		)
		(sheetname "/DCDC/")
		(sheetfile "dcdc.kicad_sch")
		(attr smd)
		(fp_line
			(start -0.3 0.7)
			(end 0.3 0.7)
			(stroke
				(width 0.15)
				(type solid)
			)
			(layer "F.SilkS")
		)
		(fp_line
			(start -0.3 -0.7)
			(end 0.3 -0.7)
			(stroke
				(width 0.15)
				(type solid)
			)
			(layer "F.SilkS")
		)
		(fp_rect
			(start 1.95 -0.9)
			(end -1.95 0.9)
			(stroke
				(width 0.05)
				(type default)
			)
			(fill no)
			(layer "F.CrtYd")
		)
		(fp_rect
			(start -0.95 -0.675)
			(end 0.95 0.675)
			(stroke
				(width 0.15)
				(type solid)
			)
			(fill no)
			(layer "F.Fab")
		)
		(fp_text user "License: Apache-2.0"
			(at -1.9 4.947 90)
			(layer "F.Fab")
			(effects
				(font
					(size 0.7 0.7)
					(thickness 0.15)
				)
				(justify right top)
			)
		)
		(fp_text user "Author: Antmicro"
			(at -1.9 5.947 90)
			(layer "F.Fab")
			(effects
				(font
					(size 0.7 0.7)
					(thickness 0.15)
				)
				(justify right top)
			)
		)
		(fp_text user "${REFERENCE}"
			(at -1.9 3.947 90)
			(layer "F.Fab")
			(effects
				(font
					(size 0.7 0.7)
					(thickness 0.15)
				)
				(justify right top)
			)
		)
		(pad "1" smd roundrect
			(at -1.1 0 270)
			(size 1.2 1.3)
			(layers "F.Cu" "F.Mask" "F.Paste")
			(roundrect_rratio 0.25)
			(net 1 "GND")
			(pintype "passive")
		)
		(pad "2" smd roundrect
			(at 1.1 0 270)
			(size 1.2 1.3)
			(layers "F.Cu" "F.Mask" "F.Paste")
			(roundrect_rratio 0.25)
			(net 1105 "/DCDC/20V_OUT")
			(pintype "passive")
		)
	)
)
